# S9S_MB_2U (Grand Teton) — schematic netlist excerpt (pin names and nets, part order shuffled) for the footprints in the layout excerpt that follows; sources: Cadence DE-HDL packaged netlist, KiCad conversion of 03242023_DA0F0TMBIJ0_F0T_Motherboard_J_brd_V01_OCP.brd

C922  Q_CAP_DIFFBUS  DIFF BUS_0.22UF 6.3V 20% X6S  pkg C0201  page 173 : \1\ = P5E_CPU0_PE0_TX_C_DN<5> ; \2\ = P5E_CPU0_PE0_TX_DN<5>
C2390  Q_CAP  100NF 50V 10% EMPTY  pkg C0402  page 306 : A = P12V_AUX ; B = GND
R938  Q_RES  10K 1% CHIP  pkg 0402LF  page 128 : A = RST_CPU0_DRAM_GH_N ; B = GND

(kicad_pcb
	(version 20260206)
	(generator "pcbnew")
	(generator_version "10.0")
	(general
		(thickness 1.6)
		(legacy_teardrops no)
	)
	(paper "A4")
	(title_block
		(title "03242023_DA0F0TMBIJ0_F0T_Motherboard_J_brd_V01_OCP.brd")
		(comment 1 "Grand Teton / footprints 3514-3516 of 6105")
	)
	(layers
		(0 "F.Cu" signal "TOP")
		(4 "In1.Cu" signal "GND")
		(6 "In2.Cu" signal "IN1")
		(8 "In3.Cu" signal "GND1")
		(10 "In4.Cu" signal "IN2")
		(12 "In5.Cu" signal "GND2")
		(14 "In6.Cu" signal "IN3")
		(16 "In7.Cu" signal "GND3")
		(18 "In8.Cu" signal "VCC")
		(20 "In9.Cu" signal "VCC1")
		(22 "In10.Cu" signal "GND4")
		(24 "In11.Cu" signal "IN4")
		(26 "In12.Cu" signal "GND5")
		(28 "In13.Cu" signal "IN5")
		(30 "In14.Cu" signal "GND6")
		(32 "In15.Cu" signal "IN6")
		(34 "In16.Cu" signal "GND7")
		(2 "B.Cu" signal "BOTTOM")
		(9 "F.Adhes" user "F.Adhesive")
		(11 "B.Adhes" user "B.Adhesive")
		(13 "F.Paste" user "Package Geometry/Pastemask Top")
		(15 "B.Paste" user "Package Geometry/Pastemask Bottom")
		(5 "F.SilkS" user "Ref Des/Silkscreen Top")
		(7 "B.SilkS" user "Ref Des/Silkscreen Bottom")
		(1 "F.Mask" user "Board Geometry/Soldermask Top")
		(3 "B.Mask" user "Board Geometry/Soldermask Bottom")
		(17 "Dwgs.User" user "User.Drawings")
		(19 "Cmts.User" user "User.Comments")
		(21 "Eco1.User" user "User.Eco1")
		(23 "Eco2.User" user "User.Eco2")
		(25 "Edge.Cuts" user "Board Geometry/Outline")
		(27 "Margin" user)
		(31 "F.CrtYd" user "Package Geometry/Place Bound Top")
		(29 "B.CrtYd" user "Package Geometry/Place Bound Bottom")
		(35 "F.Fab" user "Ref Des/Assembly Top")
		(33 "B.Fab" user "Ref Des/Assembly Bottom")
	)
	(footprint ""
		(layer "F.Cu")
		(at 182.82158 -417.7157)
		(property "Reference" "C2390"
			(at 0 0 0)
			(layer "F.SilkS")
			(hide yes)
			(effects
				(font
					(size 1.27 1.27)
				)
			)
		)
		(property "Value" ""
			(at 0 0 0)
			(layer "F.Fab")
			(effects
				(font
					(size 1.27 1.27)
				)
			)
		)
		(duplicate_pad_numbers_are_jumpers no)
		(fp_line
			(start -0.7874 -0.4064)
			(end 0.7874 -0.4064)
			(stroke
				(width 0.1524)
				(type default)
			)
			(layer "F.SilkS")
		)
		(fp_line
			(start -0.7874 0.4064)
			(end -0.7874 -0.4064)
			(stroke
				(width 0.1524)
				(type default)
			)
			(layer "F.SilkS")
		)
		(fp_line
			(start 0.7874 -0.4064)
			(end 0.7874 0.4064)
			(stroke
				(width 0.1524)
				(type default)
			)
			(layer "F.SilkS")
		)
		(fp_line
			(start 0.7874 0.4064)
			(end -0.7874 0.4064)
			(stroke
				(width 0.1524)
				(type default)
			)
			(layer "F.SilkS")
		)
		(fp_line
			(start -0.67945 -0.305054)
			(end -0.12065 -0.305054)
			(stroke
				(width 0.1)
				(type default)
			)
			(layer "F.Fab")
		)
		(fp_line
			(start -0.67945 0.3048)
			(end -0.67945 -0.305054)
			(stroke
				(width 0.1)
				(type default)
			)
			(layer "F.Fab")
		)
		(fp_line
			(start -0.12065 -0.305054)
			(end -0.12065 -0.2794)
			(stroke
				(width 0.1)
				(type default)
			)
			(layer "F.Fab")
		)
		(fp_line
			(start -0.12065 -0.2794)
			(end 0.12065 -0.2794)
			(stroke
				(width 0.1)
				(type default)
			)
			(layer "F.Fab")
		)
		(fp_line
			(start -0.12065 0.2794)
			(end -0.12065 0.3048)
			(stroke
				(width 0.1)
				(type default)
			)
			(layer "F.Fab")
		)
		(fp_line
			(start -0.12065 0.3048)
			(end -0.67945 0.3048)
			(stroke
				(width 0.1)
				(type default)
			)
			(layer "F.Fab")
		)
		(fp_line
			(start 0.120396 0.2794)
			(end -0.12065 0.2794)
			(stroke
				(width 0.1)
				(type default)
			)
			(layer "F.Fab")
		)
		(fp_line
			(start 0.120396 0.3048)
			(end 0.120396 0.2794)
			(stroke
				(width 0.1)
				(type default)
			)
			(layer "F.Fab")
		)
		(fp_line
			(start 0.12065 -0.3048)
			(end 0.67945 -0.3048)
			(stroke
				(width 0.1)
				(type default)
			)
			(layer "F.Fab")
		)
		(fp_line
			(start 0.12065 -0.2794)
			(end 0.12065 -0.3048)
			(stroke
				(width 0.1)
				(type default)
			)
			(layer "F.Fab")
		)
		(fp_line
			(start 0.67945 -0.3048)
			(end 0.67945 0.3048)
			(stroke
				(width 0.1)
				(type default)
			)
			(layer "F.Fab")
		)
		(fp_line
			(start 0.67945 0.3048)
			(end 0.120396 0.3048)
			(stroke
				(width 0.1)
				(type default)
			)
			(layer "F.Fab")
		)
		(pad "1" smd circle
			(at -0.40005 0)
			(size 0 0)
			(layers "F.Cu" "F.Mask" "F.Paste")
			(net "P12V_AUX")
		)
		(pad "2" smd circle
			(at 0.40005 0)
			(size 0 0)
			(layers "F.Cu" "F.Mask" "F.Paste")
			(net "GND")
		)
	)
	(footprint ""
		(layer "F.Cu")
		(at 117.22608 -122.132598 90)
		(property "Reference" "R938"
			(at 0 0 90)
			(layer "F.SilkS")
			(hide yes)
			(effects
				(font
					(size 1.27 1.27)
				)
			)
		)
		(property "Value" ""
			(at 0 0 90)
			(layer "F.Fab")
			(effects
				(font
					(size 1.27 1.27)
				)
			)
		)
		(duplicate_pad_numbers_are_jumpers no)
		(fp_line
			(start 0.7874 -0.4064)
			(end 0.7874 0.4064)
			(stroke
				(width 0.1524)
				(type default)
			)
			(layer "F.SilkS")
		)
		(fp_line
			(start -0.7874 -0.4064)
			(end 0.7874 -0.4064)
			(stroke
				(width 0.1524)
				(type default)
			)
			(layer "F.SilkS")
		)
		(fp_line
			(start 0.7874 0.4064)
			(end -0.7874 0.4064)
			(stroke
				(width 0.1524)
				(type default)
			)
			(layer "F.SilkS")
		)
		(fp_line
			(start -0.7874 0.4064)
			(end -0.7874 -0.4064)
			(stroke
				(width 0.1524)
				(type default)
			)
			(layer "F.SilkS")
		)
		(fp_line
			(start -0.12065 -0.305054)
			(end -0.12065 -0.2794)
			(stroke
				(width 0.1)
				(type default)
			)
			(layer "F.Fab")
		)
		(fp_line
			(start -0.67945 -0.305054)
			(end -0.12065 -0.305054)
			(stroke
				(width 0.1)
				(type default)
			)
			(layer "F.Fab")
		)
		(fp_line
			(start 0.67945 -0.3048)
			(end 0.67945 0.3048)
			(stroke
				(width 0.1)
				(type default)
			)
			(layer "F.Fab")
		)
		(fp_line
			(start 0.12065 -0.3048)
			(end 0.67945 -0.3048)
			(stroke
				(width 0.1)
				(type default)
			)
			(layer "F.Fab")
		)
		(fp_line
			(start 0.12065 -0.2794)
			(end 0.12065 -0.3048)
			(stroke
				(width 0.1)
				(type default)
			)
			(layer "F.Fab")
		)
		(fp_line
			(start -0.12065 -0.2794)
			(end 0.12065 -0.2794)
			(stroke
				(width 0.1)
				(type default)
			)
			(layer "F.Fab")
		)
		(fp_line
			(start 0.120396 0.2794)
			(end -0.12065 0.2794)
			(stroke
				(width 0.1)
				(type default)
			)
			(layer "F.Fab")
		)
		(fp_line
			(start -0.12065 0.2794)
			(end -0.12065 0.3048)
			(stroke
				(width 0.1)
				(type default)
			)
			(layer "F.Fab")
		)
		(fp_line
			(start 0.67945 0.3048)
			(end 0.120396 0.3048)
			(stroke
				(width 0.1)
				(type default)
			)
			(layer "F.Fab")
		)
		(fp_line
			(start 0.120396 0.3048)
			(end 0.120396 0.2794)
			(stroke
				(width 0.1)
				(type default)
			)
			(layer "F.Fab")
		)
		(fp_line
			(start -0.12065 0.3048)
			(end -0.67945 0.3048)
			(stroke
				(width 0.1)
				(type default)
			)
			(layer "F.Fab")
		)
		(fp_line
			(start -0.67945 0.3048)
			(end -0.67945 -0.305054)
			(stroke
				(width 0.1)
				(type default)
			)
			(layer "F.Fab")
		)
		(pad "1" smd circle
			(at -0.40005 0 90)
			(size 0 0)
			(layers "F.Cu" "F.Mask" "F.Paste")
			(net "RST_CPU0_DRAM_GH_N")
		)
		(pad "2" smd circle
			(at 0.40005 0 90)
			(size 0 0)
			(layers "F.Cu" "F.Mask" "F.Paste")
			(net "GND")
		)
	)
	(footprint ""
		(layer "F.Cu")
		(at 335.933288 -408.517344 -90)
		(property "Reference" "C922"
			(at 0 0 270)
			(layer "F.SilkS")
			(hide yes)
			(effects
				(font
					(size 1.27 1.27)
				)
			)
		)
		(property "Value" ""
			(at 0 0 270)
			(layer "F.Fab")
			(effects
				(font
					(size 1.27 1.27)
				)
			)
		)
		(duplicate_pad_numbers_are_jumpers no)
		(fp_line
			(start -0.299974 0.150114)
			(end -0.299974 -0.150114)
			(stroke
				(width 0.1)
				(type default)
			)
			(layer "F.Fab")
		)
		(fp_line
			(start 0.299974 0.150114)
			(end -0.299974 0.150114)
			(stroke
				(width 0.1)
				(type default)
			)
			(layer "F.Fab")
		)
		(fp_line
			(start -0.299974 -0.150114)
			(end 0.299974 -0.150114)
			(stroke
				(width 0.1)
				(type default)
			)
			(layer "F.Fab")
		)
		(fp_line
			(start 0.299974 -0.150114)
			(end 0.299974 0.150114)
			(stroke
				(width 0.1)
				(type default)
			)
			(layer "F.Fab")
		)
		(pad "1" smd rect
			(at -0.2667 0 270)
			(size 0.3048 0.381)
			(layers "F.Cu" "F.Mask" "F.Paste")
			(net "P5E_CPU0_PE0_TX_C_DN<5>")
		)
		(pad "2" smd rect
			(at 0.2667 0 270)
			(size 0.3048 0.381)
			(layers "F.Cu" "F.Mask" "F.Paste")
			(net "P5E_CPU0_PE0_TX_DN<5>")
		)
	)
)
